FILE_TYPE = CONNECTIVITY;
{Allegro Design Entry HDL 16.6-p007 (v16-6-112F) 10/10/2012}
"PAGE_NUMBER" = 86;
0"NC";
1"M_L_DQS_DN<17:0>";
2"M_L_DQS_DP<17:0>";
3"M_L_MA<17:0>";
4"M_L_DQ<63:0>";
5"M_L_CLK_DN<3:0>";
6"M_L_CLK_DP<3:0>";
7"M_L_BG<1:0>";
8"M_L_BA<1:0>";
9"M_L_CS_N<7:0>";
10"M_L_CKE<3:0>";
11"M_L_ODT<3:0>";
12"M_L_ECC<7:0>";
13"GND\g";
14"GND\g";
15"GND\g";
16"P12V_NVDIMM_KLM\g";
17"GND\g";
18"PVPP_KLM\g";
19"PVDDQ_KLM\g";
20"PVTT_KLM\g";
21"PVPP_KLM\g";
22"M_L_ACT_N";
23"M_L_VREF";
24"TP_CH_L_DIMM0_RFU_2";
25"TP_CH_L_DIMM0_RFU_0";
26"TP_CH_L_DIMM0_RFU_1";
27"SMB_DDR_KLM_VPP_SCL";
28"SMB_DDR_KLM_VPP_SDA";
29"M_L_ALERT_N";
30"FM_ADR_COMPLETE_KLM_N";
31"M_L_DQ<1>";
32"M_L_DQ<0>";
33"M_L_DQ<2>";
34"M_L_DQ<12>";
35"M_L_DQ<11>";
36"M_L_DQ<10>";
37"M_L_DQ<8>";
38"M_L_DQ<6>";
39"M_L_DQ<4>";
40"M_L_DQ<5>";
41"M_L_DQ<7>";
42"M_L_DQ<9>";
43"M_L_DQ<3>";
44"FM_DIMM_EVENT_COD_N";
45"M_KLM_RST_N";
46"M_L_PAR";
47"M_L_CS_N<6>";
48"M_L_CS_N<5>";
49"M_L_ECC<6>";
50"M_L_ECC<5>";
51"M_L_ECC<4>";
52"M_L_ECC<3>";
53"M_L_ECC<2>";
54"M_L_ECC<1>";
55"M_L_ECC<0>";
56"M_L_CKE<3>";
57"M_L_ECC<7>";
58"M_L_ODT<2>";
59"M_L_ODT<3>";
60"M_L_CKE<2>";
61"M_L_CS_N<4>";
62"M_L_C<2>";
63"M_L_BA<1>";
64"M_L_CS_N<7>";
65"M_L_MA<0>";
66"M_L_MA<1>";
67"M_L_MA<3>";
68"M_L_MA<4>";
69"M_L_MA<5>";
70"M_L_MA<6>";
71"M_L_MA<7>";
72"M_L_BG<1>";
73"M_L_BA<0>";
74"M_L_MA<2>";
75"M_L_BG<0>";
76"M_L_CLK_DP<2>";
77"M_L_CLK_DP<3>";
78"M_L_CLK_DN<3>";
79"M_L_CLK_DN<2>";
80"M_L_DQ<22>";
81"M_L_DQ<21>";
82"M_L_DQ<20>";
83"M_L_DQ<19>";
84"M_L_DQ<18>";
85"M_L_DQ<16>";
86"M_L_DQ<14>";
87"M_L_DQ<13>";
88"M_L_DQ<15>";
89"M_L_DQ<17>";
90"M_L_DQ<29>";
91"M_L_DQ<28>";
92"M_L_DQ<32>";
93"M_L_DQ<31>";
94"M_L_DQ<30>";
95"M_L_DQ<25>";
96"M_L_DQ<24>";
97"M_L_DQ<23>";
98"M_L_DQ<27>";
99"M_L_DQ<26>";
100"M_L_DQ<43>";
101"M_L_DQ<42>";
102"M_L_DQ<41>";
103"M_L_DQ<40>";
104"M_L_DQ<39>";
105"M_L_DQ<37>";
106"M_L_DQ<34>";
107"M_L_DQ<33>";
108"M_L_DQ<35>";
109"M_L_DQ<36>";
110"M_L_DQ<38>";
111"M_L_DQ<46>";
112"M_L_DQ<45>";
113"M_L_DQ<44>";
114"M_L_DQ<53>";
115"M_L_DQ<52>";
116"M_L_DQ<51>";
117"M_L_DQ<50>";
118"M_L_DQ<49>";
119"M_L_DQ<48>";
120"M_L_DQ<47>";
121"M_L_MA<12>";
122"M_L_MA<13>";
123"M_L_MA<17>";
124"M_L_MA<8>";
125"M_L_MA<9>";
126"M_L_MA<10>";
127"M_L_MA<11>";
128"M_L_MA<14>";
129"M_L_MA<15>";
130"M_L_MA<16>";
131"M_L_DQ<63>";
132"M_L_DQ<62>";
133"M_L_DQ<61>";
134"M_L_DQ<60>";
135"M_L_DQ<59>";
136"M_L_DQ<56>";
137"M_L_DQ<55>";
138"M_L_DQ<57>";
139"M_L_DQ<58>";
140"M_L_DQ<54>";
141"M_L_DQS_DP<0>";
142"M_L_DQS_DP<1>";
143"M_L_DQS_DP<2>";
144"M_L_DQS_DP<3>";
145"M_L_DQS_DP<4>";
146"M_L_DQS_DN<0>";
147"M_L_DQS_DN<1>";
148"M_L_DQS_DN<2>";
149"M_L_DQS_DN<3>";
150"M_L_DQS_DN<4>";
151"M_L_DQS_DN<5>";
152"M_L_DQS_DP<5>";
153"M_L_DQS_DP<6>";
154"M_L_DQS_DP<7>";
155"M_L_DQS_DP<8>";
156"M_L_DQS_DP<9>";
157"M_L_DQS_DN<10>";
158"M_L_DQS_DN<6>";
159"M_L_DQS_DN<7>";
160"M_L_DQS_DN<8>";
161"M_L_DQS_DN<9>";
162"M_L_DQS_DP<10>";
163"M_L_DQS_DP<11>";
164"M_L_DQS_DP<12>";
165"M_L_DQS_DP<13>";
166"M_L_DQS_DP<14>";
167"M_L_DQS_DN<11>";
168"M_L_DQS_DN<12>";
169"M_L_DQS_DN<13>";
170"M_L_DQS_DN<14>";
171"M_L_DQS_DN<15>";
172"M_L_DQS_DP<15>";
173"M_L_DQS_DP<16>";
174"M_L_DQS_DP<17>";
175"M_L_DQS_DN<16>";
176"M_L_DQS_DN<17>";
%"GND"
"1","(-3525,1525)","2","mstr_symbols","I1";
;
HDL_POWER"GND"
ROOM"DDR4_CH_D"
BODY_TYPE"PLUMBING"
BOM_COST"MEM"
SIZE"1B"
CDS_LIB"mstr_symbols"
VOLTAGE"0";
"A\NAC"13;
%"SCONN288_H44441003"
"2","(1625,3975)","0","mstr_sconn","I100";
;
CDS_SEC"2"
ROOM"DDR4_CH_L"
CDS_LOCATION"J9L2"
SEC"2"
SEC_TYPE"PIP"
CDS_LIB"mstr_sconn"
BOM_COST"MEM"
PACK_TYPE"PIP"
MATERIAL"SCONN"
PART_NUMBER"H44441-003"
LOCATION"J9L2";
"DQS0N"
$PN"152"146;
"DQS0P"
$PN"153"141;
"DQS10N"
$PN"19"157;
"DQS10P"
$PN"18"162;
"DQS11N"
$PN"30"167;
"DQS11P"
$PN"29"163;
"DQS12N"
$PN"41"168;
"DQS12P"
$PN"40"164;
"DQS13N"
$PN"100"169;
"DQS13P"
$PN"99"165;
"DQS14N"
$PN"111"170;
"DQS14P"
$PN"110"166;
"DQS15N"
$PN"122"171;
"DQS15P"
$PN"121"172;
"DQS16N"
$PN"133"175;
"DQS16P"
$PN"132"173;
"DQS17N"
$PN"52"176;
"DQS17P"
$PN"51"174;
"DQS1N"
$PN"163"147;
"DQS1P"
$PN"164"142;
"DQS2N"
$PN"174"148;
"DQS2P"
$PN"175"143;
"DQS3N"
$PN"185"149;
"DQS3P"
$PN"186"144;
"DQS4N"
$PN"244"150;
"DQS4P"
$PN"245"145;
"DQS5N"
$PN"255"151;
"DQS5P"
$PN"256"152;
"DQS6N"
$PN"266"158;
"DQS6P"
$PN"267"153;
"DQS7N"
$PN"277"159;
"DQS7P"
$PN"278"154;
"DQS8N"
$PN"196"160;
"DQS8P"
$PN"197"155;
"DQS9N"
$PN"8"161;
"DQS9P"
$PN"7"156;
%"TAP"
"6","(-1625,3775)","0","mstr_standard","I102";
;
HDL_TAP"TRUE"
BODY_TYPE"PLUMBING"
CDS_LIB"mstr_standard";
"B \NAC \NWC"3;
"S \NAC"
BN"1"66;
%"TAP"
"6","(-1625,3825)","0","mstr_standard","I103";
;
HDL_TAP"TRUE"
BODY_TYPE"PLUMBING"
CDS_LIB"mstr_standard";
"B \NAC \NWC"3;
"S \NAC"
BN"2"74;
%"TAP"
"6","(-1625,3875)","0","mstr_standard","I104";
;
HDL_TAP"TRUE"
BODY_TYPE"PLUMBING"
CDS_LIB"mstr_standard";
"B \NAC \NWC"3;
"S \NAC"
BN"3"67;
%"TAP"
"6","(-1625,3975)","0","mstr_standard","I105";
;
HDL_TAP"TRUE"
BODY_TYPE"PLUMBING"
CDS_LIB"mstr_standard";
"B \NAC \NWC"3;
"S \NAC"
BN"5"69;
%"TAP"
"6","(-1625,3925)","0","mstr_standard","I106";
;
HDL_TAP"TRUE"
BODY_TYPE"PLUMBING"
CDS_LIB"mstr_standard";
"B \NAC \NWC"3;
"S \NAC"
BN"4"68;
%"TAP"
"6","(-1625,4025)","0","mstr_standard","I107";
;
HDL_TAP"TRUE"
BODY_TYPE"PLUMBING"
CDS_LIB"mstr_standard";
"B \NAC \NWC"3;
"S \NAC"
BN"6"70;
%"TAP"
"6","(-1625,4125)","0","mstr_standard","I108";
;
HDL_TAP"TRUE"
BODY_TYPE"PLUMBING"
CDS_LIB"mstr_standard";
"B \NAC \NWC"3;
"S \NAC"
BN"8"124;
%"TAP"
"6","(-1625,4075)","0","mstr_standard","I109";
;
HDL_TAP"TRUE"
BODY_TYPE"PLUMBING"
CDS_LIB"mstr_standard";
"B \NAC \NWC"3;
"S \NAC"
BN"7"71;
%"TAP"
"6","(-1625,4175)","0","mstr_standard","I110";
;
HDL_TAP"TRUE"
BODY_TYPE"PLUMBING"
CDS_LIB"mstr_standard";
"B \NAC \NWC"3;
"S \NAC"
BN"9"125;
%"TAP"
"6","(-1625,4225)","0","mstr_standard","I111";
;
HDL_TAP"TRUE"
BODY_TYPE"PLUMBING"
CDS_LIB"mstr_standard";
"B \NAC \NWC"3;
"S \NAC"
BN"10"126;
%"TAP"
"6","(-1625,4275)","0","mstr_standard","I112";
;
HDL_TAP"TRUE"
BODY_TYPE"PLUMBING"
CDS_LIB"mstr_standard";
"B \NAC \NWC"3;
"S \NAC"
BN"11"127;
%"TAP"
"6","(-1625,4375)","0","mstr_standard","I113";
;
HDL_TAP"TRUE"
BODY_TYPE"PLUMBING"
CDS_LIB"mstr_standard";
"B \NAC \NWC"3;
"S \NAC"
BN"13"122;
%"TAP"
"6","(-1625,4325)","0","mstr_standard","I114";
;
HDL_TAP"TRUE"
BODY_TYPE"PLUMBING"
CDS_LIB"mstr_standard";
"B \NAC \NWC"3;
"S \NAC"
BN"12"121;
%"TAP"
"6","(-1625,4425)","0","mstr_standard","I115";
;
HDL_TAP"TRUE"
BODY_TYPE"PLUMBING"
CDS_LIB"mstr_standard";
"B \NAC \NWC"3;
"S \NAC"
BN"14"128;
%"TAP"
"6","(-1625,4475)","0","mstr_standard","I116";
;
HDL_TAP"TRUE"
BODY_TYPE"PLUMBING"
CDS_LIB"mstr_standard";
"B \NAC \NWC"3;
"S \NAC"
BN"15"129;
%"TAP"
"6","(-1625,4525)","0","mstr_standard","I117";
;
HDL_TAP"TRUE"
BODY_TYPE"PLUMBING"
CDS_LIB"mstr_standard";
"B \NAC \NWC"3;
"S \NAC"
BN"16"130;
%"TAP"
"6","(-1625,4575)","0","mstr_standard","I118";
;
HDL_TAP"TRUE"
BODY_TYPE"PLUMBING"
CDS_LIB"mstr_standard";
"B \NAC \NWC"3;
"S \NAC"
BN"17"123;
%"TAP"
"6","(-125,3925)","2","mstr_standard","I119";
;
HDL_TAP"TRUE"
BODY_TYPE"PLUMBING"
CDS_LIB"mstr_standard";
"B \NAC \NWC"4;
"S \NAC"
BN"50"117;
%"SCONN288_H44441003"
"1","(-875,2925)","0","mstr_sconn","I12";
;
CDS_SEC"1"
ROOM"DDR4_CH_L"
CDS_LOCATION"J9L2"
SEC"1"
SEC_TYPE"PIP"
CDS_LIB"mstr_sconn"
BOM_COST"MEM"
PACK_TYPE"PIP"
MATERIAL"SCONN"
PART_NUMBER"H44441-003"
LOCATION"J9L2";
"DQ<63>"
$PN"280"131;
"BA<1>"
$PN"224"63;
"CK1N"
$PN"219"78;
"CK0P"
$PN"74"76;
"S3_N_C<1>"
$PN"237"64;
"S2_N_C<0>"
$PN"93"47;
"S1_N"
$PN"89"48;
"DQ<29>"
$PN"181"90;
"DQ<28>"
$PN"36"91;
"C<2>"
$PN"235"62;
"A0"
$PN"79"65;
"A1"
$PN"72"66;
"A12"
$PN"65"121;
"A13"
$PN"232"122;
"A17"
$PN"234"123;
"A3"
$PN"71"67;
"A4"
$PN"214"68;
"A5"
$PN"213"69;
"A6"
$PN"69"70;
"A7"
$PN"211"71;
"A8"
$PN"68"124;
"A9"
$PN"66"125;
"CB<6>"
$PN"54"49;
"CB<5>"
$PN"192"50;
"CB<4>"
$PN"47"51;
"CB<3>"
$PN"201"52;
"CB<2>"
$PN"56"53;
"CB<1>"
$PN"194"54;
"CB<0>"
$PN"49"55;
"CK0N"
$PN"75"79;
"CKE<1>"
$PN"203"56;
"DQ<62>"
$PN"135"132;
"DQ<61>"
$PN"273"133;
"DQ<60>"
$PN"128"134;
"DQ<59>"
$PN"282"135;
"DQ<56>"
$PN"130"136;
"DQ<55>"
$PN"269"137;
"DQ<46>"
$PN"113"111;
"DQ<45>"
$PN"251"112;
"DQ<44>"
$PN"106"113;
"DQ<43>"
$PN"260"100;
"DQ<42>"
$PN"115"101;
"DQ<41>"
$PN"253"102;
"DQ<40>"
$PN"108"103;
"DQ<39>"
$PN"247"104;
"DQ<37>"
$PN"240"105;
"DQ<34>"
$PN"104"106;
"DQ<33>"
$PN"242"107;
"DQ<32>"
$PN"97"92;
"DQ<31>"
$PN"188"93;
"DQ<30>"
$PN"43"94;
"DQ<25>"
$PN"183"95;
"DQ<24>"
$PN"38"96;
"DQ<23>"
$PN"177"97;
"DQ<22>"
$PN"32"80;
"DQ<21>"
$PN"170"81;
"DQ<20>"
$PN"25"82;
"DQ<19>"
$PN"179"83;
"DQ<18>"
$PN"34"84;
"DQ<16>"
$PN"27"85;
"DQ<14>"
$PN"21"86;
"DQ<13>"
$PN"159"87;
"DQ<12>"
$PN"14"34;
"DQ<11>"
$PN"168"35;
"DQ<10>"
$PN"23"36;
"DQ<9>"
$PN"161"42;
"DQ<8>"
$PN"16"37;
"DQ<7>"
$PN"155"41;
"DQ<6>"
$PN"10"38;
"EVENT_N"
$PN"78"44;
"PAR"
$PN"222"46;
"RESET_N"
$PN"58"45;
"RFU<2>"
$PN"144"24;
"SCL"
$PN"141"27;
"SDA"
$PN"285"28;
"VREFCA"
$PN"146"23;
"CK1P"
$PN"218"77;
"BG<0>"
$PN"63"75;
"BG<1>"
$PN"207"72;
"BA<0>"
$PN"81"73;
"SA<0>"
$PN"139"18;
"VDDSPD"
$PN"284"18;
"SA<2>"
$PN"238"13;
"SA<1>"
$PN"140"18;
"DQ<1>"
$PN"150"31;
"DQ<0>"
$PN"5"32;
"ACT_N"
$PN"62"22;
"ALERT_N"
$PN"208"29;
"A2"
$PN"216"74;
"DQ<35>"
$PN"249"108;
"DQ<36>"
$PN"95"109;
"DQ<38>"
$PN"102"110;
"A10"
$PN"225"126;
"A11"
$PN"210"127;
"A14_WE_N"
$PN"228"128;
"A15_CAS_N"
$PN"86"129;
"A16_RAS_N"
$PN"82"130;
"CB<7>"
$PN"199"57;
"ODT<0>"
$PN"87"58;
"ODT<1>"
$PN"91"59;
"CKE<0>"
$PN"60"60;
"S0_N"
$PN"84"61;
"DQ<27>"
$PN"190"98;
"DQ<26>"
$PN"45"99;
"DQ<15>"
$PN"166"88;
"DQ<17>"
$PN"172"89;
"RFU<0>"
$PN"205"25;
"RFU<1>"
$PN"227"26;
"SAVE_N_NC"
$PN"230"30;
"DQ<57>"
$PN"275"138;
"DQ<58>"
$PN"137"139;
"DQ<54>"
$PN"124"140;
"DQ<53>"
$PN"262"114;
"DQ<52>"
$PN"117"115;
"DQ<51>"
$PN"271"116;
"DQ<50>"
$PN"126"117;
"DQ<49>"
$PN"264"118;
"DQ<48>"
$PN"119"119;
"DQ<47>"
$PN"258"120;
"DQ<2>"
$PN"12"33;
"DQ<3>"
$PN"157"43;
"DQ<4>"
$PN"3"39;
"DQ<5>"
$PN"148"40;
%"TAP"
"6","(-125,3975)","2","mstr_standard","I120";
;
HDL_TAP"TRUE"
BODY_TYPE"PLUMBING"
CDS_LIB"mstr_standard";
"B \NAC \NWC"4;
"S \NAC"
BN"51"116;
%"TAP"
"6","(-125,3875)","2","mstr_standard","I121";
;
HDL_TAP"TRUE"
BODY_TYPE"PLUMBING"
CDS_LIB"mstr_standard";
"B \NAC \NWC"4;
"S \NAC"
BN"49"118;
%"TAP"
"6","(-125,3775)","2","mstr_standard","I122";
;
HDL_TAP"TRUE"
BODY_TYPE"PLUMBING"
CDS_LIB"mstr_standard";
"B \NAC \NWC"4;
"S \NAC"
BN"47"120;
%"TAP"
"6","(-125,3825)","2","mstr_standard","I123";
;
HDL_TAP"TRUE"
BODY_TYPE"PLUMBING"
CDS_LIB"mstr_standard";
"B \NAC \NWC"4;
"S \NAC"
BN"48"119;
%"TAP"
"6","(-125,4025)","2","mstr_standard","I124";
;
HDL_TAP"TRUE"
BODY_TYPE"PLUMBING"
CDS_LIB"mstr_standard";
"B \NAC \NWC"4;
"S \NAC"
BN"52"115;
%"TAP"
"6","(-125,4175)","2","mstr_standard","I125";
;
HDL_TAP"TRUE"
BODY_TYPE"PLUMBING"
CDS_LIB"mstr_standard";
"B \NAC \NWC"4;
"S \NAC"
BN"55"137;
%"TAP"
"6","(-125,4225)","2","mstr_standard","I126";
;
HDL_TAP"TRUE"
BODY_TYPE"PLUMBING"
CDS_LIB"mstr_standard";
"B \NAC \NWC"4;
"S \NAC"
BN"56"136;
%"TAP"
"6","(-125,4275)","2","mstr_standard","I127";
;
HDL_TAP"TRUE"
BODY_TYPE"PLUMBING"
CDS_LIB"mstr_standard";
"B \NAC \NWC"4;
"S \NAC"
BN"57"138;
%"TAP"
"6","(-125,4075)","2","mstr_standard","I128";
;
HDL_TAP"TRUE"
BODY_TYPE"PLUMBING"
CDS_LIB"mstr_standard";
"B \NAC \NWC"4;
"S \NAC"
BN"53"114;
%"TAP"
"6","(-125,4125)","2","mstr_standard","I129";
;
HDL_TAP"TRUE"
BODY_TYPE"PLUMBING"
CDS_LIB"mstr_standard";
"B \NAC \NWC"4;
"S \NAC"
BN"54"140;
%"TAP"
"6","(-125,4375)","2","mstr_standard","I130";
;
HDL_TAP"TRUE"
BODY_TYPE"PLUMBING"
CDS_LIB"mstr_standard";
"B \NAC \NWC"4;
"S \NAC"
BN"59"135;
%"TAP"
"6","(-125,4325)","2","mstr_standard","I131";
;
HDL_TAP"TRUE"
BODY_TYPE"PLUMBING"
CDS_LIB"mstr_standard";
"B \NAC \NWC"4;
"S \NAC"
BN"58"139;
%"TAP"
"6","(-125,4525)","2","mstr_standard","I132";
;
HDL_TAP"TRUE"
BODY_TYPE"PLUMBING"
CDS_LIB"mstr_standard";
"B \NAC \NWC"4;
"S \NAC"
BN"62"132;
%"TAP"
"6","(-125,4425)","2","mstr_standard","I133";
;
HDL_TAP"TRUE"
BODY_TYPE"PLUMBING"
CDS_LIB"mstr_standard";
"B \NAC \NWC"4;
"S \NAC"
BN"60"134;
%"TAP"
"6","(-125,4475)","2","mstr_standard","I134";
;
HDL_TAP"TRUE"
BODY_TYPE"PLUMBING"
CDS_LIB"mstr_standard";
"B \NAC \NWC"4;
"S \NAC"
BN"61"133;
%"TAP"
"6","(-125,4575)","2","mstr_standard","I135";
;
HDL_TAP"TRUE"
BODY_TYPE"PLUMBING"
CDS_LIB"mstr_standard";
"B \NAC \NWC"4;
"S \NAC"
BN"63"131;
%"GND"
"1","(2725,775)","2","mstr_symbols","I137";
;
HDL_POWER"GND"
ROOM"DDR4_CH_D"
BODY_TYPE"PLUMBING"
BOM_COST"MEM"
CDS_LIB"mstr_symbols"
SIZE"1B"
VOLTAGE"0";
"A\NAC"14;
%"SCONN288_H44441003"
"3","(3425,2075)","0","mstr_sconn","I138";
;
CDS_SEC"3"
ROOM"DDR4_CH_L"
CDS_LOCATION"J9L2"
SEC"3"
SEC_TYPE"PIP"
CDS_LIB"mstr_sconn"
BOM_COST"MEM"
PACK_TYPE"PIP"
MATERIAL"SCONN"
PART_NUMBER"H44441-003"
LOCATION"J9L2";
"VSS<46>"
$PN"147"15;
"VSS<45>"
$PN"149"15;
"VSS<87>"
$PN"15"14;
"VSS<86>"
$PN"17"14;
"VSS<85>"
$PN"20"14;
"VSS<84>"
$PN"22"14;
"VSS<83>"
$PN"24"14;
"VSS<82>"
$PN"26"14;
"VSS<81>"
$PN"28"14;
"VSS<80>"
$PN"31"14;
"VSS<79>"
$PN"33"14;
"VSS<78>"
$PN"35"14;
"VSS<77>"
$PN"37"14;
"VSS<76>"
$PN"39"14;
"VSS<75>"
$PN"42"14;
"VSS<74>"
$PN"44"14;
"VSS<73>"
$PN"46"14;
"VSS<72>"
$PN"48"14;
"VSS<71>"
$PN"50"14;
"VSS<70>"
$PN"53"14;
"VSS<69>"
$PN"55"14;
"VSS<68>"
$PN"57"14;
"VSS<67>"
$PN"94"14;
"VSS<66>"
$PN"96"14;
"VSS<65>"
$PN"98"14;
"VSS<64>"
$PN"101"14;
"VSS<63>"
$PN"103"14;
"VSS<62>"
$PN"105"14;
"VSS<61>"
$PN"107"14;
"VSS<60>"
$PN"109"14;
"VSS<59>"
$PN"112"14;
"VSS<58>"
$PN"114"14;
"VSS<57>"
$PN"116"14;
"VSS<56>"
$PN"118"14;
"VSS<55>"
$PN"120"14;
"VSS<54>"
$PN"123"14;
"VSS<53>"
$PN"125"14;
"VSS<52>"
$PN"127"14;
"VSS<51>"
$PN"129"14;
"VSS<50>"
$PN"131"14;
"VSS<49>"
$PN"134"14;
"VSS<48>"
$PN"136"14;
"VSS<47>"
$PN"138"14;
"VSS<44>"
$PN"151"15;
"VSS<43>"
$PN"154"15;
"VSS<42>"
$PN"156"15;
"VSS<41>"
$PN"158"15;
"VSS<40>"
$PN"160"15;
"VSS<39>"
$PN"162"15;
"VSS<38>"
$PN"165"15;
"VSS<37>"
$PN"167"15;
"VSS<36>"
$PN"169"15;
"VSS<35>"
$PN"171"15;
"VSS<34>"
$PN"173"15;
"VSS<33>"
$PN"176"15;
"VSS<32>"
$PN"178"15;
"VSS<31>"
$PN"180"15;
"VSS<30>"
$PN"182"15;
"VSS<29>"
$PN"184"15;
"VSS<28>"
$PN"187"15;
"VSS<27>"
$PN"189"15;
"VSS<26>"
$PN"191"15;
"VSS<25>"
$PN"193"15;
"VSS<24>"
$PN"195"15;
"VSS<23>"
$PN"198"15;
"VSS<22>"
$PN"200"15;
"VSS<21>"
$PN"202"15;
"VSS<20>"
$PN"239"15;
"VSS<19>"
$PN"241"15;
"VSS<18>"
$PN"243"15;
"VSS<17>"
$PN"246"15;
"VSS<16>"
$PN"248"15;
"VSS<15>"
$PN"250"15;
"VSS<14>"
$PN"252"15;
"VSS<13>"
$PN"254"15;
"VSS<12>"
$PN"257"15;
"VSS<11>"
$PN"259"15;
"VSS<10>"
$PN"261"15;
"VSS<9>"
$PN"263"15;
"VSS<8>"
$PN"265"15;
"VSS<7>"
$PN"268"15;
"VSS<6>"
$PN"270"15;
"VSS<5>"
$PN"272"15;
"VSS<4>"
$PN"274"15;
"VSS<3>"
$PN"276"15;
"VSS<2>"
$PN"279"15;
"VSS<1>"
$PN"281"15;
"VSS<0>"
$PN"283"15;
"VSS<88>"
$PN"13"14;
"VSS<89>"
$PN"11"14;
"VSS<90>"
$PN"9"14;
"VSS<91>"
$PN"6"14;
"VSS<92>"
$PN"4"14;
"VSS<93>"
$PN"2"14;
%"TAP"
"6","(2325,3125)","2","mstr_standard","I142";
;
HDL_TAP"TRUE"
BODY_TYPE"PLUMBING"
CDS_LIB"mstr_standard";
"B \NAC \NWC"2;
"S \NAC"
BN"0"141;
%"TAP"
"6","(2325,3225)","2","mstr_standard","I143";
;
HDL_TAP"TRUE"
BODY_TYPE"PLUMBING"
CDS_LIB"mstr_standard";
"B \NAC \NWC"2;
"S \NAC"
BN"1"142;
%"TAP"
"6","(2525,3075)","2","mstr_standard","I144";
;
HDL_TAP"TRUE"
BODY_TYPE"PLUMBING"
CDS_LIB"mstr_standard";
"B \NAC \NWC"1;
"S \NAC"
BN"0"146;
%"TAP"
"6","(2525,3175)","2","mstr_standard","I145";
;
HDL_TAP"TRUE"
BODY_TYPE"PLUMBING"
CDS_LIB"mstr_standard";
"B \NAC \NWC"1;
"S \NAC"
BN"1"147;
%"TAP"
"6","(2325,3325)","2","mstr_standard","I146";
;
HDL_TAP"TRUE"
BODY_TYPE"PLUMBING"
CDS_LIB"mstr_standard";
"B \NAC \NWC"2;
"S \NAC"
BN"2"143;
%"TAP"
"6","(2325,3425)","2","mstr_standard","I147";
;
HDL_TAP"TRUE"
BODY_TYPE"PLUMBING"
CDS_LIB"mstr_standard";
"B \NAC \NWC"2;
"S \NAC"
BN"3"144;
%"TAP"
"6","(2325,3625)","2","mstr_standard","I148";
;
HDL_TAP"TRUE"
BODY_TYPE"PLUMBING"
CDS_LIB"mstr_standard";
"B \NAC \NWC"2;
"S \NAC"
BN"5"152;
%"TAP"
"6","(2325,3525)","2","mstr_standard","I149";
;
HDL_TAP"TRUE"
BODY_TYPE"PLUMBING"
CDS_LIB"mstr_standard";
"B \NAC \NWC"2;
"S \NAC"
BN"4"145;
%"TAP"
"6","(2325,3725)","2","mstr_standard","I150";
;
HDL_TAP"TRUE"
BODY_TYPE"PLUMBING"
CDS_LIB"mstr_standard";
"B \NAC \NWC"2;
"S \NAC"
BN"6"153;
%"TAP"
"6","(2525,3475)","2","mstr_standard","I151";
;
HDL_TAP"TRUE"
BODY_TYPE"PLUMBING"
CDS_LIB"mstr_standard";
"B \NAC \NWC"1;
"S \NAC"
BN"4"150;
%"TAP"
"6","(2525,3275)","2","mstr_standard","I152";
;
HDL_TAP"TRUE"
BODY_TYPE"PLUMBING"
CDS_LIB"mstr_standard";
"B \NAC \NWC"1;
"S \NAC"
BN"2"148;
%"TAP"
"6","(2525,3375)","2","mstr_standard","I153";
;
HDL_TAP"TRUE"
BODY_TYPE"PLUMBING"
CDS_LIB"mstr_standard";
"B \NAC \NWC"1;
"S \NAC"
BN"3"149;
%"TAP"
"6","(2525,3675)","2","mstr_standard","I154";
;
HDL_TAP"TRUE"
BODY_TYPE"PLUMBING"
CDS_LIB"mstr_standard";
"B \NAC \NWC"1;
"S \NAC"
BN"6"158;
%"TAP"
"6","(2525,3575)","2","mstr_standard","I155";
;
HDL_TAP"TRUE"
BODY_TYPE"PLUMBING"
CDS_LIB"mstr_standard";
"B \NAC \NWC"1;
"S \NAC"
BN"5"151;
%"GND"
"1","(4125,775)","2","mstr_symbols","I156";
;
HDL_POWER"GND"
ROOM"DDR4_CH_D"
BODY_TYPE"PLUMBING"
BOM_COST"MEM"
CDS_LIB"mstr_symbols"
SIZE"1B"
VOLTAGE"0";
"A\NAC"15;
%"TAP"
"6","(2325,3825)","2","mstr_standard","I157";
;
HDL_TAP"TRUE"
BODY_TYPE"PLUMBING"
CDS_LIB"mstr_standard";
"B \NAC \NWC"2;
"S \NAC"
BN"7"154;
%"TAP"
"6","(2325,4025)","2","mstr_standard","I158";
;
HDL_TAP"TRUE"
BODY_TYPE"PLUMBING"
CDS_LIB"mstr_standard";
"B \NAC \NWC"2;
"S \NAC"
BN"9"156;
%"TAP"
"6","(2325,3925)","2","mstr_standard","I159";
;
HDL_TAP"TRUE"
BODY_TYPE"PLUMBING"
CDS_LIB"mstr_standard";
"B \NAC \NWC"2;
"S \NAC"
BN"8"155;
%"TAP"
"6","(2325,4125)","2","mstr_standard","I160";
;
HDL_TAP"TRUE"
BODY_TYPE"PLUMBING"
CDS_LIB"mstr_standard";
"B \NAC \NWC"2;
"S \NAC"
BN"10"162;
%"TAP"
"6","(2325,4225)","2","mstr_standard","I161";
;
HDL_TAP"TRUE"
BODY_TYPE"PLUMBING"
CDS_LIB"mstr_standard";
"B \NAC \NWC"2;
"S \NAC"
BN"11"163;
%"TAP"
"6","(2525,3975)","2","mstr_standard","I162";
;
HDL_TAP"TRUE"
BODY_TYPE"PLUMBING"
CDS_LIB"mstr_standard";
"B \NAC \NWC"1;
"S \NAC"
BN"9"161;
%"TAP"
"6","(2525,3775)","2","mstr_standard","I163";
;
HDL_TAP"TRUE"
BODY_TYPE"PLUMBING"
CDS_LIB"mstr_standard";
"B \NAC \NWC"1;
"S \NAC"
BN"7"159;
%"TAP"
"6","(2525,3875)","2","mstr_standard","I164";
;
HDL_TAP"TRUE"
BODY_TYPE"PLUMBING"
CDS_LIB"mstr_standard";
"B \NAC \NWC"1;
"S \NAC"
BN"8"160;
%"TAP"
"6","(2525,4175)","2","mstr_standard","I165";
;
HDL_TAP"TRUE"
BODY_TYPE"PLUMBING"
CDS_LIB"mstr_standard";
"B \NAC \NWC"1;
"S \NAC"
BN"11"167;
%"TAP"
"6","(2525,4075)","2","mstr_standard","I166";
;
HDL_TAP"TRUE"
BODY_TYPE"PLUMBING"
CDS_LIB"mstr_standard";
"B \NAC \NWC"1;
"S \NAC"
BN"10"157;
%"TAP"
"6","(2525,4275)","2","mstr_standard","I167";
;
HDL_TAP"TRUE"
BODY_TYPE"PLUMBING"
CDS_LIB"mstr_standard";
"B \NAC \NWC"1;
"S \NAC"
BN"12"168;
%"TAP"
"6","(2325,4325)","2","mstr_standard","I168";
;
HDL_TAP"TRUE"
BODY_TYPE"PLUMBING"
CDS_LIB"mstr_standard";
"B \NAC \NWC"2;
"S \NAC"
BN"12"164;
%"TAP"
"6","(2325,4525)","2","mstr_standard","I169";
;
HDL_TAP"TRUE"
BODY_TYPE"PLUMBING"
CDS_LIB"mstr_standard";
"B \NAC \NWC"2;
"S \NAC"
BN"14"166;
%"TAP"
"6","(-1625,2225)","0","mstr_standard","I17";
;
HDL_TAP"TRUE"
BODY_TYPE"PLUMBING"
CDS_LIB"mstr_standard";
"B \NAC \NWC"12;
"S \NAC"
BN"1"54;
%"TAP"
"6","(2325,4425)","2","mstr_standard","I170";
;
HDL_TAP"TRUE"
BODY_TYPE"PLUMBING"
CDS_LIB"mstr_standard";
"B \NAC \NWC"2;
"S \NAC"
BN"13"165;
%"TAP"
"6","(2325,4625)","2","mstr_standard","I171";
;
HDL_TAP"TRUE"
BODY_TYPE"PLUMBING"
CDS_LIB"mstr_standard";
"B \NAC \NWC"2;
"S \NAC"
BN"15"172;
%"TAP"
"6","(2325,4725)","2","mstr_standard","I172";
;
HDL_TAP"TRUE"
BODY_TYPE"PLUMBING"
CDS_LIB"mstr_standard";
"B \NAC \NWC"2;
"S \NAC"
BN"16"173;
%"TAP"
"6","(2525,4375)","2","mstr_standard","I173";
;
HDL_TAP"TRUE"
BODY_TYPE"PLUMBING"
CDS_LIB"mstr_standard";
"B \NAC \NWC"1;
"S \NAC"
BN"13"169;
%"TAP"
"6","(2525,4475)","2","mstr_standard","I174";
;
HDL_TAP"TRUE"
BODY_TYPE"PLUMBING"
CDS_LIB"mstr_standard";
"B \NAC \NWC"1;
"S \NAC"
BN"14"170;
%"TAP"
"6","(2525,4775)","2","mstr_standard","I175";
;
HDL_TAP"TRUE"
BODY_TYPE"PLUMBING"
CDS_LIB"mstr_standard";
"B \NAC \NWC"1;
"S \NAC"
BN"17"176;
%"TAP"
"6","(2525,4675)","2","mstr_standard","I176";
;
HDL_TAP"TRUE"
BODY_TYPE"PLUMBING"
CDS_LIB"mstr_standard";
"B \NAC \NWC"1;
"S \NAC"
BN"16"175;
%"TAP"
"6","(2525,4575)","2","mstr_standard","I177";
;
HDL_TAP"TRUE"
BODY_TYPE"PLUMBING"
CDS_LIB"mstr_standard";
"B \NAC \NWC"1;
"S \NAC"
BN"15"171;
%"TAP"
"6","(2325,4825)","2","mstr_standard","I178";
;
HDL_TAP"TRUE"
BODY_TYPE"PLUMBING"
CDS_LIB"mstr_standard";
"B \NAC \NWC"2;
"S \NAC"
BN"17"174;
%"TAP"
"6","(-1625,2175)","0","mstr_standard","I18";
;
HDL_TAP"TRUE"
BODY_TYPE"PLUMBING"
CDS_LIB"mstr_standard";
"B \NAC \NWC"12;
"S \NAC"
BN"0"55;
%"P12V_NVDIMM_KLM"
"1","(2000,2700)","0","mstr_symbols","I181";
;
HDL_POWER"P12V_NVDIMM_KLM"
BODY_TYPE"PLUMBING"
CDS_LIB"mstr_symbols"
VOLTAGE"12.0";
"G\NAC"16;
%"CAP_A"
"1","(-3025,1225)","2","dev_discrete","I182";
;
ROOM"DDR4_CH_D"
$SEC"1"
CDS_SEC"1"
CDS_LIB"dev_discrete"
BOM_COST"MEM"
CDS_LOCATION"C1A17"
MATERIAL"X7R"
VOLTAGE"25V"
PACK_TYPE"0402V"
TOLERANCE"10%"
VALUE"0.01UF"
PART_NUMBER"A36096-045"
LOCATION"C1A17";
"B"
$PN"2"17;
"A"
$PN"1"23;
%"TAP"
"6","(-1625,2325)","0","mstr_standard","I19";
;
HDL_TAP"TRUE"
BODY_TYPE"PLUMBING"
CDS_LIB"mstr_standard";
"B \NAC \NWC"12;
"S \NAC"
BN"3"52;
%"GND"
"1","(-3025,975)","0","mstr_symbols","I2";
;
HDL_POWER"GND"
ROOM"DDR4_CH_D"
BODY_TYPE"PLUMBING"
BOM_COST"MEM"
CDS_LIB"mstr_symbols"
SIZE"1B"
VOLTAGE"0";
"A\NAC"17;
%"TAP"
"6","(-1625,2275)","0","mstr_standard","I20";
;
HDL_TAP"TRUE"
BODY_TYPE"PLUMBING"
CDS_LIB"mstr_standard";
"B \NAC \NWC"12;
"S \NAC"
BN"2"53;
%"TAP"
"6","(-1625,2375)","0","mstr_standard","I21";
;
HDL_TAP"TRUE"
BODY_TYPE"PLUMBING"
CDS_LIB"mstr_standard";
"B \NAC \NWC"12;
"S \NAC"
BN"4"51;
%"TAP"
"6","(-1625,2425)","0","mstr_standard","I22";
;
HDL_TAP"TRUE"
BODY_TYPE"PLUMBING"
CDS_LIB"mstr_standard";
"B \NAC \NWC"12;
"S \NAC"
BN"5"50;
%"TAP"
"6","(-1625,2475)","0","mstr_standard","I23";
;
HDL_TAP"TRUE"
BODY_TYPE"PLUMBING"
CDS_LIB"mstr_standard";
"B \NAC \NWC"12;
"S \NAC"
BN"6"49;
%"TAP"
"6","(-1625,2525)","0","mstr_standard","I24";
;
HDL_TAP"TRUE"
BODY_TYPE"PLUMBING"
CDS_LIB"mstr_standard";
"B \NAC \NWC"12;
"S \NAC"
BN"7"57;
%"TAP"
"6","(-1625,2675)","0","mstr_standard","I25";
;
HDL_TAP"TRUE"
BODY_TYPE"PLUMBING"
CDS_LIB"mstr_standard";
"B \NAC \NWC"11;
"S \NAC"
BN"3"59;
%"TAP"
"6","(-1625,2625)","0","mstr_standard","I26";
;
HDL_TAP"TRUE"
BODY_TYPE"PLUMBING"
CDS_LIB"mstr_standard";
"B \NAC \NWC"11;
"S \NAC"
BN"2"58;
%"TAP"
"6","(-1825,3225)","0","mstr_standard","I34";
;
HDL_TAP"TRUE"
BODY_TYPE"PLUMBING"
CDS_LIB"mstr_standard";
"B \NAC \NWC"5;
"S \NAC"
BN"2"79;
%"TAP"
"6","(-1625,2825)","0","mstr_standard","I35";
;
HDL_TAP"TRUE"
BODY_TYPE"PLUMBING"
CDS_LIB"mstr_standard";
"B \NAC \NWC"10;
"S \NAC"
BN"3"56;
%"TAP"
"6","(-1625,2775)","0","mstr_standard","I36";
;
HDL_TAP"TRUE"
BODY_TYPE"PLUMBING"
CDS_LIB"mstr_standard";
"B \NAC \NWC"10;
"S \NAC"
BN"2"60;
%"TAP"
"6","(-1625,2975)","0","mstr_standard","I37";
;
HDL_TAP"TRUE"
BODY_TYPE"PLUMBING"
CDS_LIB"mstr_standard";
"B \NAC \NWC"9;
"S \NAC"
BN"5"48;
%"TAP"
"6","(-1625,2925)","0","mstr_standard","I38";
;
HDL_TAP"TRUE"
BODY_TYPE"PLUMBING"
CDS_LIB"mstr_standard";
"B \NAC \NWC"9;
"S \NAC"
BN"4"61;
%"TAP"
"6","(-1625,3075)","0","mstr_standard","I39";
;
HDL_TAP"TRUE"
BODY_TYPE"PLUMBING"
CDS_LIB"mstr_standard";
"B \NAC \NWC"9;
"S \NAC"
BN"7"64;
%"TAP"
"6","(-1625,3025)","0","mstr_standard","I40";
;
HDL_TAP"TRUE"
BODY_TYPE"PLUMBING"
CDS_LIB"mstr_standard";
"B \NAC \NWC"9;
"S \NAC"
BN"6"47;
%"TAP"
"6","(-1825,3325)","0","mstr_standard","I41";
;
HDL_TAP"TRUE"
BODY_TYPE"PLUMBING"
CDS_LIB"mstr_standard";
"B \NAC \NWC"5;
"S \NAC"
BN"3"78;
%"TAP"
"6","(-1625,3275)","0","mstr_standard","I42";
;
HDL_TAP"TRUE"
BODY_TYPE"PLUMBING"
CDS_LIB"mstr_standard";
"B \NAC \NWC"6;
"S \NAC"
BN"2"76;
%"TAP"
"6","(-1625,3375)","0","mstr_standard","I43";
;
HDL_TAP"TRUE"
BODY_TYPE"PLUMBING"
CDS_LIB"mstr_standard";
"B \NAC \NWC"6;
"S \NAC"
BN"3"77;
%"TAP"
"6","(-1625,3475)","0","mstr_standard","I44";
;
HDL_TAP"TRUE"
BODY_TYPE"PLUMBING"
CDS_LIB"mstr_standard";
"B \NAC \NWC"7;
"S \NAC"
BN"0"75;
%"TAP"
"6","(-1625,3575)","0","mstr_standard","I45";
;
HDL_TAP"TRUE"
BODY_TYPE"PLUMBING"
CDS_LIB"mstr_standard";
"B \NAC \NWC"8;
"S \NAC"
BN"0"73;
%"TAP"
"6","(-1625,3525)","0","mstr_standard","I46";
;
HDL_TAP"TRUE"
BODY_TYPE"PLUMBING"
CDS_LIB"mstr_standard";
"B \NAC \NWC"7;
"S \NAC"
BN"1"72;
%"TAP"
"6","(-1625,3625)","0","mstr_standard","I47";
;
HDL_TAP"TRUE"
BODY_TYPE"PLUMBING"
CDS_LIB"mstr_standard";
"B \NAC \NWC"8;
"S \NAC"
BN"1"63;
%"TAP"
"6","(-1625,3725)","0","mstr_standard","I48";
;
HDL_TAP"TRUE"
BODY_TYPE"PLUMBING"
CDS_LIB"mstr_standard";
"B \NAC \NWC"3;
"S \NAC"
BN"0"65;
%"TAP"
"6","(-125,1425)","2","mstr_standard","I49";
;
HDL_TAP"TRUE"
BODY_TYPE"PLUMBING"
CDS_LIB"mstr_standard";
"B \NAC \NWC"4;
"S \NAC"
BN"0"32;
%"PVPP_KLM"
"1","(-3525,1925)","0","mstr_symbols","I5";
;
HDL_POWER"PVPP_KLM"
ROOM"DDR4_CH_D"
BODY_TYPE"PLUMBING"
CDS_LIB"mstr_symbols"
BOM_COST"MEM"
VOLTAGE"2.5V";
"G\NAC"18;
%"TAP"
"6","(-125,1625)","2","mstr_standard","I50";
;
HDL_TAP"TRUE"
BODY_TYPE"PLUMBING"
CDS_LIB"mstr_standard";
"B \NAC \NWC"4;
"S \NAC"
BN"4"39;
%"TAP"
"6","(-125,1475)","2","mstr_standard","I51";
;
HDL_TAP"TRUE"
BODY_TYPE"PLUMBING"
CDS_LIB"mstr_standard";
"B \NAC \NWC"4;
"S \NAC"
BN"1"31;
%"TAP"
"6","(-125,1525)","2","mstr_standard","I52";
;
HDL_TAP"TRUE"
BODY_TYPE"PLUMBING"
CDS_LIB"mstr_standard";
"B \NAC \NWC"4;
"S \NAC"
BN"2"33;
%"TAP"
"6","(-125,1675)","2","mstr_standard","I53";
;
HDL_TAP"TRUE"
BODY_TYPE"PLUMBING"
CDS_LIB"mstr_standard";
"B \NAC \NWC"4;
"S \NAC"
BN"5"40;
%"TAP"
"6","(-125,1575)","2","mstr_standard","I54";
;
HDL_TAP"TRUE"
BODY_TYPE"PLUMBING"
CDS_LIB"mstr_standard";
"B \NAC \NWC"4;
"S \NAC"
BN"3"43;
%"SCONN288_H44441003"
"4","(1375,1725)","0","mstr_sconn","I55";
;
CDS_SEC"4"
ROOM"DDR4_CH_L"
CDS_LOCATION"J9L2"
SEC"4"
SEC_TYPE"PIP"
CDS_LIB"mstr_sconn"
BOM_COST"MEM"
PACK_TYPE"PIP"
MATERIAL"SCONN"
PART_NUMBER"H44441-003"
LOCATION"J9L2";
"VDD<0>"
$PN"236"19;
"VDD<6>"
$PN"220"19;
"VDD<10>"
$PN"209"19;
"VDD<13>"
$PN"92"19;
"VDD<16>"
$PN"85"19;
"VDD<19>"
$PN"76"19;
"VDD<23>"
$PN"64"19;
"VDD<25>"
$PN"59"19;
"VTT<0>"
$PN"221"20;
"12V<1>"
$PN"1"16;
"12V<0>"
$PN"145"16;
"VDD<24>"
$PN"61"19;
"VDD<22>"
$PN"67"19;
"VDD<21>"
$PN"70"19;
"VDD<20>"
$PN"73"19;
"VDD<18>"
$PN"80"19;
"VDD<17>"
$PN"83"19;
"VDD<15>"
$PN"88"19;
"VDD<14>"
$PN"90"19;
"VDD<12>"
$PN"204"19;
"VDD<11>"
$PN"206"19;
"VDD<9>"
$PN"212"19;
"VDD<8>"
$PN"215"19;
"VDD<7>"
$PN"217"19;
"VDD<5>"
$PN"223"19;
"VDD<4>"
$PN"226"19;
"VDD<3>"
$PN"229"19;
"VDD<2>"
$PN"231"19;
"VDD<1>"
$PN"233"19;
"VPP<4>"
$PN"142"21;
"VPP<3>"
$PN"143"21;
"VPP<2>"
$PN"288"21;
"VPP<1>"
$PN"286"21;
"VPP<0>"
$PN"287"21;
"VTT<1>"
$PN"77"20;
%"TAP"
"6","(-125,1925)","2","mstr_standard","I56";
;
HDL_TAP"TRUE"
BODY_TYPE"PLUMBING"
CDS_LIB"mstr_standard";
"B \NAC \NWC"4;
"S \NAC"
BN"10"36;
%"TAP"
"6","(-125,1725)","2","mstr_standard","I57";
;
HDL_TAP"TRUE"
BODY_TYPE"PLUMBING"
CDS_LIB"mstr_standard";
"B \NAC \NWC"4;
"S \NAC"
BN"6"38;
%"TAP"
"6","(-125,1825)","2","mstr_standard","I58";
;
HDL_TAP"TRUE"
BODY_TYPE"PLUMBING"
CDS_LIB"mstr_standard";
"B \NAC \NWC"4;
"S \NAC"
BN"8"37;
%"TAP"
"6","(-125,1775)","2","mstr_standard","I59";
;
HDL_TAP"TRUE"
BODY_TYPE"PLUMBING"
CDS_LIB"mstr_standard";
"B \NAC \NWC"4;
"S \NAC"
BN"7"41;
%"TAP"
"6","(-125,1975)","2","mstr_standard","I60";
;
HDL_TAP"TRUE"
BODY_TYPE"PLUMBING"
CDS_LIB"mstr_standard";
"B \NAC \NWC"4;
"S \NAC"
BN"11"35;
%"TAP"
"6","(-125,1875)","2","mstr_standard","I61";
;
HDL_TAP"TRUE"
BODY_TYPE"PLUMBING"
CDS_LIB"mstr_standard";
"B \NAC \NWC"4;
"S \NAC"
BN"9"42;
%"TAP"
"6","(-125,2025)","2","mstr_standard","I62";
;
HDL_TAP"TRUE"
BODY_TYPE"PLUMBING"
CDS_LIB"mstr_standard";
"B \NAC \NWC"4;
"S \NAC"
BN"12"34;
%"TAP"
"6","(-125,2075)","2","mstr_standard","I63";
;
HDL_TAP"TRUE"
BODY_TYPE"PLUMBING"
CDS_LIB"mstr_standard";
"B \NAC \NWC"4;
"S \NAC"
BN"13"87;
%"TAP"
"6","(-125,2225)","2","mstr_standard","I64";
;
HDL_TAP"TRUE"
BODY_TYPE"PLUMBING"
CDS_LIB"mstr_standard";
"B \NAC \NWC"4;
"S \NAC"
BN"16"85;
%"TAP"
"6","(-125,2175)","2","mstr_standard","I65";
;
HDL_TAP"TRUE"
BODY_TYPE"PLUMBING"
CDS_LIB"mstr_standard";
"B \NAC \NWC"4;
"S \NAC"
BN"15"88;
%"TAP"
"6","(-125,2125)","2","mstr_standard","I66";
;
HDL_TAP"TRUE"
BODY_TYPE"PLUMBING"
CDS_LIB"mstr_standard";
"B \NAC \NWC"4;
"S \NAC"
BN"14"86;
%"TAP"
"6","(-125,2325)","2","mstr_standard","I67";
;
HDL_TAP"TRUE"
BODY_TYPE"PLUMBING"
CDS_LIB"mstr_standard";
"B \NAC \NWC"4;
"S \NAC"
BN"18"84;
%"TAP"
"6","(-125,2275)","2","mstr_standard","I68";
;
HDL_TAP"TRUE"
BODY_TYPE"PLUMBING"
CDS_LIB"mstr_standard";
"B \NAC \NWC"4;
"S \NAC"
BN"17"89;
%"TAP"
"6","(-125,2475)","2","mstr_standard","I69";
;
HDL_TAP"TRUE"
BODY_TYPE"PLUMBING"
CDS_LIB"mstr_standard";
"B \NAC \NWC"4;
"S \NAC"
BN"21"81;
%"TAP"
"6","(-125,2425)","2","mstr_standard","I70";
;
HDL_TAP"TRUE"
BODY_TYPE"PLUMBING"
CDS_LIB"mstr_standard";
"B \NAC \NWC"4;
"S \NAC"
BN"20"82;
%"TAP"
"6","(-125,2375)","2","mstr_standard","I71";
;
HDL_TAP"TRUE"
BODY_TYPE"PLUMBING"
CDS_LIB"mstr_standard";
"B \NAC \NWC"4;
"S \NAC"
BN"19"83;
%"TAP"
"6","(-125,2675)","2","mstr_standard","I72";
;
HDL_TAP"TRUE"
BODY_TYPE"PLUMBING"
CDS_LIB"mstr_standard";
"B \NAC \NWC"4;
"S \NAC"
BN"25"95;
%"TAP"
"6","(-125,2625)","2","mstr_standard","I73";
;
HDL_TAP"TRUE"
BODY_TYPE"PLUMBING"
CDS_LIB"mstr_standard";
"B \NAC \NWC"4;
"S \NAC"
BN"24"96;
%"TAP"
"6","(-125,2725)","2","mstr_standard","I74";
;
HDL_TAP"TRUE"
BODY_TYPE"PLUMBING"
CDS_LIB"mstr_standard";
"B \NAC \NWC"4;
"S \NAC"
BN"26"99;
%"TAP"
"6","(-125,2525)","2","mstr_standard","I75";
;
HDL_TAP"TRUE"
BODY_TYPE"PLUMBING"
CDS_LIB"mstr_standard";
"B \NAC \NWC"4;
"S \NAC"
BN"22"80;
%"TAP"
"6","(-125,2575)","2","mstr_standard","I76";
;
HDL_TAP"TRUE"
BODY_TYPE"PLUMBING"
CDS_LIB"mstr_standard";
"B \NAC \NWC"4;
"S \NAC"
BN"23"97;
%"PVDDQ_KLM"
"1","(275,2275)","0","mstr_symbols","I77";
;
HDL_POWER"PVDDQ_KLM"
ROOM"DDR4_CH_D"
BODY_TYPE"PLUMBING"
CDS_LIB"mstr_symbols"
BOM_COST"MEM"
VOLTAGE"1.2V";
"G\NAC"19;
%"PVTT_KLM"
"1","(525,2425)","0","mstr_symbols","I78";
;
HDL_POWER"PVTT_KLM"
ROOM"DDR4_CH_D"
BODY_TYPE"PLUMBING"
CDS_LIB"mstr_symbols"
BOM_COST"MEM"
VOLTAGE"0.6V";
"G\NAC"20;
%"TAP"
"6","(-125,2775)","2","mstr_standard","I79";
;
HDL_TAP"TRUE"
BODY_TYPE"PLUMBING"
CDS_LIB"mstr_standard";
"B \NAC \NWC"4;
"S \NAC"
BN"27"98;
%"TAP"
"6","(-125,2825)","2","mstr_standard","I80";
;
HDL_TAP"TRUE"
BODY_TYPE"PLUMBING"
CDS_LIB"mstr_standard";
"B \NAC \NWC"4;
"S \NAC"
BN"28"91;
%"TAP"
"6","(-125,2875)","2","mstr_standard","I81";
;
HDL_TAP"TRUE"
BODY_TYPE"PLUMBING"
CDS_LIB"mstr_standard";
"B \NAC \NWC"4;
"S \NAC"
BN"29"90;
%"TAP"
"6","(-125,2975)","2","mstr_standard","I82";
;
HDL_TAP"TRUE"
BODY_TYPE"PLUMBING"
CDS_LIB"mstr_standard";
"B \NAC \NWC"4;
"S \NAC"
BN"31"93;
%"TAP"
"6","(-125,2925)","2","mstr_standard","I83";
;
HDL_TAP"TRUE"
BODY_TYPE"PLUMBING"
CDS_LIB"mstr_standard";
"B \NAC \NWC"4;
"S \NAC"
BN"30"94;
%"TAP"
"6","(-125,3175)","2","mstr_standard","I84";
;
HDL_TAP"TRUE"
BODY_TYPE"PLUMBING"
CDS_LIB"mstr_standard";
"B \NAC \NWC"4;
"S \NAC"
BN"35"108;
%"TAP"
"6","(-125,3125)","2","mstr_standard","I85";
;
HDL_TAP"TRUE"
BODY_TYPE"PLUMBING"
CDS_LIB"mstr_standard";
"B \NAC \NWC"4;
"S \NAC"
BN"34"106;
%"TAP"
"6","(-125,3225)","2","mstr_standard","I86";
;
HDL_TAP"TRUE"
BODY_TYPE"PLUMBING"
CDS_LIB"mstr_standard";
"B \NAC \NWC"4;
"S \NAC"
BN"36"109;
%"TAP"
"6","(-125,3075)","2","mstr_standard","I87";
;
HDL_TAP"TRUE"
BODY_TYPE"PLUMBING"
CDS_LIB"mstr_standard";
"B \NAC \NWC"4;
"S \NAC"
BN"33"107;
%"TAP"
"6","(-125,3025)","2","mstr_standard","I88";
;
HDL_TAP"TRUE"
BODY_TYPE"PLUMBING"
CDS_LIB"mstr_standard";
"B \NAC \NWC"4;
"S \NAC"
BN"32"92;
%"TAP"
"6","(-125,3325)","2","mstr_standard","I89";
;
HDL_TAP"TRUE"
BODY_TYPE"PLUMBING"
CDS_LIB"mstr_standard";
"B \NAC \NWC"4;
"S \NAC"
BN"38"110;
%"TAP"
"6","(-125,3275)","2","mstr_standard","I90";
;
HDL_TAP"TRUE"
BODY_TYPE"PLUMBING"
CDS_LIB"mstr_standard";
"B \NAC \NWC"4;
"S \NAC"
BN"37"105;
%"TAP"
"6","(-125,3425)","2","mstr_standard","I91";
;
HDL_TAP"TRUE"
BODY_TYPE"PLUMBING"
CDS_LIB"mstr_standard";
"B \NAC \NWC"4;
"S \NAC"
BN"40"103;
%"TAP"
"6","(-125,3375)","2","mstr_standard","I92";
;
HDL_TAP"TRUE"
BODY_TYPE"PLUMBING"
CDS_LIB"mstr_standard";
"B \NAC \NWC"4;
"S \NAC"
BN"39"104;
%"TAP"
"6","(-125,3475)","2","mstr_standard","I93";
;
HDL_TAP"TRUE"
BODY_TYPE"PLUMBING"
CDS_LIB"mstr_standard";
"B \NAC \NWC"4;
"S \NAC"
BN"41"102;
%"TAP"
"6","(-125,3625)","2","mstr_standard","I94";
;
HDL_TAP"TRUE"
BODY_TYPE"PLUMBING"
CDS_LIB"mstr_standard";
"B \NAC \NWC"4;
"S \NAC"
BN"44"113;
%"TAP"
"6","(-125,3675)","2","mstr_standard","I95";
;
HDL_TAP"TRUE"
BODY_TYPE"PLUMBING"
CDS_LIB"mstr_standard";
"B \NAC \NWC"4;
"S \NAC"
BN"45"112;
%"TAP"
"6","(-125,3725)","2","mstr_standard","I96";
;
HDL_TAP"TRUE"
BODY_TYPE"PLUMBING"
CDS_LIB"mstr_standard";
"B \NAC \NWC"4;
"S \NAC"
BN"46"111;
%"TAP"
"6","(-125,3575)","2","mstr_standard","I97";
;
HDL_TAP"TRUE"
BODY_TYPE"PLUMBING"
CDS_LIB"mstr_standard";
"B \NAC \NWC"4;
"S \NAC"
BN"43"100;
%"TAP"
"6","(-125,3525)","2","mstr_standard","I98";
;
HDL_TAP"TRUE"
BODY_TYPE"PLUMBING"
CDS_LIB"mstr_standard";
"B \NAC \NWC"4;
"S \NAC"
BN"42"101;
%"PVPP_KLM"
"1","(675,2750)","0","mstr_symbols","I99";
;
HDL_POWER"PVPP_KLM"
ROOM"DDR4_CH_D"
BODY_TYPE"PLUMBING"
CDS_LIB"mstr_symbols"
BOM_COST"MEM"
VOLTAGE"2.5V";
"G\NAC"21;
END.
